(kicad_pcb
	(version 20260206)
	(generator "pcbnew")
	(generator_version "10.0")
	(general
		(thickness 1.6)
		(legacy_teardrops no)
	)
	(paper "A4")
	(title_block
		(title "03242023_DA0F0TMBIJ0_F0T_Motherboard_J_brd_V01_OCP.brd")
		(comment 1 "Grand Teton / footprints 1227-1228 of 6105")
	)
	(layers
		(0 "F.Cu" signal "TOP")
		(4 "In1.Cu" signal "GND")
		(6 "In2.Cu" signal "IN1")
		(8 "In3.Cu" signal "GND1")
		(10 "In4.Cu" signal "IN2")
		(12 "In5.Cu" signal "GND2")
		(14 "In6.Cu" signal "IN3")
		(16 "In7.Cu" signal "GND3")
		(18 "In8.Cu" signal "VCC")
		(20 "In9.Cu" signal "VCC1")
		(22 "In10.Cu" signal "GND4")
		(24 "In11.Cu" signal "IN4")
		(26 "In12.Cu" signal "GND5")
		(28 "In13.Cu" signal "IN5")
		(30 "In14.Cu" signal "GND6")
		(32 "In15.Cu" signal "IN6")
		(34 "In16.Cu" signal "GND7")
		(2 "B.Cu" signal "BOTTOM")
		(9 "F.Adhes" user "F.Adhesive")
		(11 "B.Adhes" user "B.Adhesive")
		(13 "F.Paste" user "Package Geometry/Pastemask Top")
		(15 "B.Paste" user "Package Geometry/Pastemask Bottom")
		(5 "F.SilkS" user "Ref Des/Silkscreen Top")
		(7 "B.SilkS" user "Ref Des/Silkscreen Bottom")
		(1 "F.Mask" user "Board Geometry/Soldermask Top")
		(3 "B.Mask" user "Board Geometry/Soldermask Bottom")
		(17 "Dwgs.User" user "User.Drawings")
		(19 "Cmts.User" user "User.Comments")
		(21 "Eco1.User" user "User.Eco1")
		(23 "Eco2.User" user "User.Eco2")
		(25 "Edge.Cuts" user "Board Geometry/Outline")
		(27 "Margin" user)
		(31 "F.CrtYd" user "Package Geometry/Place Bound Top")
		(29 "B.CrtYd" user "Package Geometry/Place Bound Bottom")
		(35 "F.Fab" user "Ref Des/Assembly Top")
		(33 "B.Fab" user "Ref Des/Assembly Bottom")
	)
	(footprint ""
		(layer "F.Cu")
		(at 435.621176 -103.77043 90)
		(property "Reference" "PC2144"
			(at 0 0 90)
			(layer "F.SilkS")
			(hide yes)
			(effects
				(font
					(size 1.27 1.27)
				)
			)
		)
		(property "Value" ""
			(at 0 0 90)
			(layer "F.Fab")
			(effects
				(font
					(size 1.27 1.27)
				)
			)
		)
		(duplicate_pad_numbers_are_jumpers no)
		(fp_line
			(start 0.7874 -0.4064)
			(end 0.7874 0.4064)
			(stroke
				(width 0.1524)
				(type default)
			)
			(layer "F.SilkS")
		)
		(fp_line
			(start -0.7874 -0.4064)
			(end 0.7874 -0.4064)
			(stroke
				(width 0.1524)
				(type default)
			)
			(layer "F.SilkS")
		)
		(fp_line
			(start 0.7874 0.4064)
			(end -0.7874 0.4064)
			(stroke
				(width 0.1524)
				(type default)
			)
			(layer "F.SilkS")
		)
		(fp_line
			(start -0.7874 0.4064)
			(end -0.7874 -0.4064)
			(stroke
				(width 0.1524)
				(type default)
			)
			(layer "F.SilkS")
		)
		(fp_line
			(start -0.12065 -0.305054)
			(end -0.12065 -0.2794)
			(stroke
				(width 0.1)
				(type default)
			)
			(layer "F.Fab")
		)
		(fp_line
			(start -0.67945 -0.305054)
			(end -0.12065 -0.305054)
			(stroke
				(width 0.1)
				(type default)
			)
			(layer "F.Fab")
		)
		(fp_line
			(start 0.67945 -0.3048)
			(end 0.67945 0.3048)
			(stroke
				(width 0.1)
				(type default)
			)
			(layer "F.Fab")
		)
		(fp_line
			(start 0.12065 -0.3048)
			(end 0.67945 -0.3048)
			(stroke
				(width 0.1)
				(type default)
			)
			(layer "F.Fab")
		)
		(fp_line
			(start 0.12065 -0.2794)
			(end 0.12065 -0.3048)
			(stroke
				(width 0.1)
				(type default)
			)
			(layer "F.Fab")
		)
		(fp_line
			(start -0.12065 -0.2794)
			(end 0.12065 -0.2794)
			(stroke
				(width 0.1)
				(type default)
			)
			(layer "F.Fab")
		)
		(fp_line
			(start 0.120396 0.2794)
			(end -0.12065 0.2794)
			(stroke
				(width 0.1)
				(type default)
			)
			(layer "F.Fab")
		)
		(fp_line
			(start -0.12065 0.2794)
			(end -0.12065 0.3048)
			(stroke
				(width 0.1)
				(type default)
			)
			(layer "F.Fab")
		)
		(fp_line
			(start 0.67945 0.3048)
			(end 0.120396 0.3048)
			(stroke
				(width 0.1)
				(type default)
			)
			(layer "F.Fab")
		)
		(fp_line
			(start 0.120396 0.3048)
			(end 0.120396 0.2794)
			(stroke
				(width 0.1)
				(type default)
			)
			(layer "F.Fab")
		)
		(fp_line
			(start -0.12065 0.3048)
			(end -0.67945 0.3048)
			(stroke
				(width 0.1)
				(type default)
			)
			(layer "F.Fab")
		)
		(fp_line
			(start -0.67945 0.3048)
			(end -0.67945 -0.305054)
			(stroke
				(width 0.1)
				(type default)
			)
			(layer "F.Fab")
		)
		(pad "1" smd circle
			(at -0.40005 0 90)
			(size 0 0)
			(layers "F.Cu" "F.Mask" "F.Paste")
			(net "P3V3_OCP_SFF_R")
		)
		(pad "2" smd circle
			(at 0.40005 0 90)
			(size 0 0)
			(layers "F.Cu" "F.Mask" "F.Paste")
			(net "P3V3_OCP_GATE_PU202_1")
		)
	)
	(footprint ""
		(layer "F.Cu")
		(at 440.384438 -14.593316 180)
		(property "Reference" "PC2092"
			(at 0 0 180)
			(layer "F.SilkS")
			(hide yes)
			(effects
				(font
					(size 1.27 1.27)
				)
			)
		)
		(property "Value" ""
			(at 0 0 180)
			(layer "F.Fab")
			(effects
				(font
					(size 1.27 1.27)
				)
			)
		)
		(duplicate_pad_numbers_are_jumpers no)
		(fp_line
			(start 0.7874 0.4064)
			(end -0.7874 0.4064)
			(stroke
				(width 0.1524)
				(type default)
			)
			(layer "F.SilkS")
		)
		(fp_line
			(start 0.7874 -0.4064)
			(end 0.7874 0.4064)
			(stroke
				(width 0.1524)
				(type default)
			)
			(layer "F.SilkS")
		)
		(fp_line
			(start -0.7874 0.4064)
			(end -0.7874 -0.4064)
			(stroke
				(width 0.1524)
				(type default)
			)
			(layer "F.SilkS")
		)
		(fp_line
			(start -0.7874 -0.4064)
			(end 0.7874 -0.4064)
			(stroke
				(width 0.1524)
				(type default)
			)
			(layer "F.SilkS")
		)
		(fp_line
			(start 0.67945 0.3048)
			(end 0.120396 0.3048)
			(stroke
				(width 0.1)
				(type default)
			)
			(layer "F.Fab")
		)
		(fp_line
			(start 0.67945 -0.3048)
			(end 0.67945 0.3048)
			(stroke
				(width 0.1)
				(type default)
			)
			(layer "F.Fab")
		)
		(fp_line
			(start 0.12065 -0.2794)
			(end 0.12065 -0.3048)
			(stroke
				(width 0.1)
				(type default)
			)
			(layer "F.Fab")
		)
		(fp_line
			(start 0.12065 -0.3048)
			(end 0.67945 -0.3048)
			(stroke
				(width 0.1)
				(type default)
			)
			(layer "F.Fab")
		)
		(fp_line
			(start 0.120396 0.3048)
			(end 0.120396 0.2794)
			(stroke
				(width 0.1)
				(type default)
			)
			(layer "F.Fab")
		)
		(fp_line
			(start 0.120396 0.2794)
			(end -0.12065 0.2794)
			(stroke
				(width 0.1)
				(type default)
			)
			(layer "F.Fab")
		)
		(fp_line
			(start -0.12065 0.3048)
			(end -0.67945 0.3048)
			(stroke
				(width 0.1)
				(type default)
			)
			(layer "F.Fab")
		)
		(fp_line
			(start -0.12065 0.2794)
			(end -0.12065 0.3048)
			(stroke
				(width 0.1)
				(type default)
			)
			(layer "F.Fab")
		)
		(fp_line
			(start -0.12065 -0.2794)
			(end 0.12065 -0.2794)
			(stroke
				(width 0.1)
				(type default)
			)
			(layer "F.Fab")
		)
		(fp_line
			(start -0.12065 -0.305054)
			(end -0.12065 -0.2794)
			(stroke
				(width 0.1)
				(type default)
			)
			(layer "F.Fab")
		)
		(fp_line
			(start -0.67945 0.3048)
			(end -0.67945 -0.305054)
			(stroke
				(width 0.1)
				(type default)
			)
			(layer "F.Fab")
		)
		(fp_line
			(start -0.67945 -0.305054)
			(end -0.12065 -0.305054)
			(stroke
				(width 0.1)
				(type default)
			)
			(layer "F.Fab")
		)
		(pad "1" smd circle
			(at -0.40005 0 180)
			(size 0 0)
			(layers "F.Cu" "F.Mask" "F.Paste")
			(net "P12V_OCP_SFF")
		)
		(pad "2" smd circle
			(at 0.40005 0 180)
			(size 0 0)
			(layers "F.Cu" "F.Mask" "F.Paste")
			(net "GND")
		)
	)
)
